FILE_TYPE = CONNECTIVITY;
{Allegro Design Entry HDL 17.2-2016 S067 (3860444) 4/26/2020}
"PAGE_NUMBER" = 12;
0"NC";
1"XP3R3V_FPGA\g";
2"SG\g";
3"SG\g";
4"SG\g";
5"SG\g";
6"SG\g";
7"SG\g";
8"SG\g";
9"SG\g";
10"SG\g";
11"SG\g";
12"SG\g";
13"SG\g";
14"SG\g";
15"XP3R3V_FPGA\g";
16"SG\g";
17"XP3R3V_FPGA\g";
18"SG\g";
19"XP3R3V_FPGA\g";
20"XP3R3V_FPGA\g";
21"XP3R3V_FPGA\g";
22"SG\g";
23"XP3R3V_FPGA\g";
24"SG\g";
25"XP3R3V_FPGA\g";
26"SG\g";
27"ANT1_OUT";
28"SMA2_SIG_OUT_BF_EN_N";
29"SMA2_SIG_IN_BF_EN_N";
30"SMA3_SIG_OUT_BF_EN_N";
31"SMA1_SIG_OUT_BF_EN_N";
32"SMA2_SIG_IO_CONN";
33"SMA1_SIG_IO_CONN";
34"SMA4_SIG_IN_BF_EN_N";
35"SMA4_SIG_OUT_BF_EN_N";
36"ANT4_OUT";
37"SMA1_SIG_IN_BF_EN_N";
38"ANT3_OUT";
39"SMA3_SIG_IN_BF_EN_N";
40"UN$12$74HCT2G125DPTSSOP8$I226$1A";
41"BF_SMA3_SIG_IO_CONN";
42"BF_ANT3_IN";
43"UN$12$74HCT2G125DPTSSOP8$I204$1A";
44"BF_SMA4_SIG_IO_CONN";
45"BF_ANT4_IN";
46"ANT2_OUT";
47"SMA4_SIG_IO_CONN";
48"ANT4_IN";
49"ANT1_IN";
50"BF_ANT2_IN";
51"ANT3_IN";
52"SMA3_SIG_IO_CONN";
53"BF_SMA2_SIG_IO_CONN";
54"BF_SMA1_SIG_IO_CONN";
55"UN$12$74HCT2G125DPTSSOP8$I273$1A";
56"UN$12$CAPACITOR$I332$2";
57"UN$12$CAPACITOR$I328$2";
58"UN$12$CAPACITOR$I321$2";
59"UN$12$CAPACITOR$I318$2";
60"UN$12$74HCT2G125DPTSSOP8$I255$1A";
61"BF_ANT1_IN";
62"ANT2_IN";
%"GND_SG"
"1","(-3700,3100)","0","cls","I120";
;
HDL_POWER"SG"
BODY_TYPE"PLUMBING"
CDS_LIB"cls"
CDS_LMAN_SYM_OUTLINE"0,0,100,-50";
"SGND"26;
%"DIODE_4_V1"
"1","(-3750,3350)","1","discrete","I179";
;
CDS_LOCATION"CR4"
PART_NUMBER"SR3.3.TCT"
CLS_PN"G122-10123-01"
CDS_LMAN_SYM_OUTLINE"0,0,400,-600"
CDS_LIB"discrete"
LOCATION"CR4"
$SEC"1"
CDS_SEC"1";
"VDD"
$PN"4"0;
"IO2"
$PN"3"33;
"IO1"
$PN"2"32;
"GND"
$PN"1"26;
%"RESISTOR"
"2","(-6400,9050)","3","passive","I197";
;
CDS_LOCATION"R122"
PACKAGE"0402"
VALUE"49.9OHM"
CDS_LIB"passive"
CDS_LMAN_SYM_OUTLINE"-50,50,50,-100"
TOLERANCE"1%"
CLS_PN"G155-149R9-01"
LOCATION"R122"
$SEC"1"
CDS_SEC"1";
"1"
$PN"1"41;
"2"
$PN"2"52;
%"74HCT2G125DP_TSSOP8"
"1","(-9550,9250)","0","stdlogic","I204";
;
CDS_LOCATION"U13"
VALUE"NC7WV125K8X"
CLS_PN"G220-00055-01"
CDS_LIB"stdlogic"
CDS_LMAN_SYM_OUTLINE"0,0,500,-500"
LOCATION"U13"
$SEC"1"
CDS_SEC"1";
"VCC"
$PN"8"25;
"2OE* \B"
$PN"7"39;
"1Y"
$PN"6"41;
"2A"
$PN"5"41;
"GND"
$PN"4"24;
"2Y"
$PN"3"42;
"1A"
$PN"2"43;
"1OE* \B"
$PN"1"30;
%"RESISTOR"
"2","(-10750,9400)","1","passive","I206";
;
CDS_LOCATION"R377"
VALUE"4.7KOHM"
PACKAGE"0402"
CDS_LIB"passive"
CDS_LMAN_SYM_OUTLINE"-50,50,50,-100"
CLS_PN"G155-14701-01"
TOLERANCE"1%"
LOCATION"R377"
$SEC"1"
CDS_SEC"1";
"1"
$PN"1"1;
"2"
$PN"2"39;
%"CAPACITOR"
"2","(-8450,8750)","0","passive","I207";
;
VOLTAGE"10V"
PACKAGE"0402"
VALUE"0.1UF"
CDS_LMAN_SYM_OUTLINE"-50,0,50,-50"
CDS_LIB"passive"
TOLERANCE"10%"
CLS_PN"G105-0B104-CK"
$LOCATION"C83"
CDS_LOCATION"C83"
$SEC"1"
CDS_SEC"1";
"2"
$PN"2"24;
"1"
$PN"1"25;
%"RESISTOR"
"2","(-6400,8950)","3","passive","I209";
;
VALUE"49.9OHM"
PACKAGE"0402"
CDS_LMAN_SYM_OUTLINE"-50,50,50,-100"
CDS_LIB"passive"
TOLERANCE"1%"
CLS_PN"G155-149R9-01"
$LOCATION"R367"
CDS_LOCATION"R367"
$SEC"1"
CDS_SEC"1";
"1"
$PN"1"42;
"2"
$PN"2"51;
%"VCC"
"1","(-8500,9300)","0","cls","I210";
;
VOLTAGE"3.3V"
HDL_POWER"XP3R3V_FPGA"
BODY_TYPE"PLUMBING"
CDS_LMAN_SYM_OUTLINE"-250,250,250,-250"
CDS_LIB"cls";
"$PIN0"25;
%"GND_SG"
"1","(-8800,8400)","0","cls","I211";
;
HDL_POWER"SG"
BODY_TYPE"PLUMBING"
CDS_LIB"cls"
CDS_LMAN_SYM_OUTLINE"0,0,100,-50";
"SGND"24;
%"74HCT2G125DP_TSSOP8"
"1","(-9500,7100)","0","stdlogic","I226";
;
CDS_LOCATION"U14"
VALUE"NC7WV125K8X"
CLS_PN"G220-00055-01"
CDS_LMAN_SYM_OUTLINE"0,0,500,-500"
CDS_LIB"stdlogic"
LOCATION"U14"
$SEC"1"
CDS_SEC"1";
"VCC"
$PN"8"23;
"2OE* \B"
$PN"7"34;
"1Y"
$PN"6"44;
"2A"
$PN"5"44;
"GND"
$PN"4"22;
"2Y"
$PN"3"45;
"1A"
$PN"2"40;
"1OE* \B"
$PN"1"35;
%"RESISTOR"
"2","(-6350,6900)","3","passive","I228";
;
CDS_LOCATION"R123"
VALUE"49.9OHM"
PACKAGE"0402"
CDS_LMAN_SYM_OUTLINE"-50,50,50,-100"
CDS_LIB"passive"
TOLERANCE"1%"
CLS_PN"G155-149R9-01"
LOCATION"R123"
$SEC"1"
CDS_SEC"1";
"1"
$PN"1"44;
"2"
$PN"2"47;
%"RESISTOR"
"2","(-6350,6800)","3","passive","I229";
;
CDS_LOCATION"R370"
PACKAGE"0402"
VALUE"49.9OHM"
CDS_LIB"passive"
CDS_LMAN_SYM_OUTLINE"-50,50,50,-100"
TOLERANCE"1%"
CLS_PN"G155-149R9-01"
LOCATION"R370"
$SEC"1"
CDS_SEC"1";
"1"
$PN"1"45;
"2"
$PN"2"48;
%"VCC"
"1","(-8450,7150)","0","cls","I230";
;
HDL_POWER"XP3R3V_FPGA"
VOLTAGE"3.3V"
BODY_TYPE"PLUMBING"
CDS_LIB"cls"
CDS_LMAN_SYM_OUTLINE"-250,250,250,-250";
"$PIN0"23;
%"CAPACITOR"
"2","(-8400,6600)","0","passive","I231";
;
CDS_LOCATION"C82"
VOLTAGE"10V"
PACKAGE"0402"
VALUE"0.1UF"
CLS_PN"G105-0B104-CK"
TOLERANCE"10%"
CDS_LIB"passive"
CDS_LMAN_SYM_OUTLINE"-50,0,50,-50"
LOCATION"C82"
$SEC"1"
CDS_SEC"1";
"2"
$PN"2"22;
"1"
$PN"1"23;
%"GND_SG"
"1","(-8750,6250)","0","cls","I232";
;
HDL_POWER"SG"
BODY_TYPE"PLUMBING"
CDS_LIB"cls"
CDS_LMAN_SYM_OUTLINE"0,0,100,-50";
"SGND"22;
%"RESISTOR"
"2","(-10700,7350)","1","passive","I233";
;
CDS_LOCATION"R368"
VALUE"4.7KOHM"
PACKAGE"0402"
CLS_PN"G155-14701-01"
CDS_LMAN_SYM_OUTLINE"-50,50,50,-100"
CDS_LIB"passive"
TOLERANCE"1%"
LOCATION"R368"
$SEC"1"
CDS_SEC"1";
"1"
$PN"1"21;
"2"
$PN"2"35;
%"RESISTOR"
"2","(-10700,7250)","1","passive","I234";
;
CDS_LOCATION"R379"
PACKAGE"0402"
VALUE"4.7KOHM"
CDS_LIB"passive"
CDS_LMAN_SYM_OUTLINE"-50,50,50,-100"
CLS_PN"G155-14701-01"
TOLERANCE"1%"
LOCATION"R379"
$SEC"1"
CDS_SEC"1";
"1"
$PN"1"21;
"2"
$PN"2"34;
%"VCC"
"1","(-11350,7450)","0","cls","I236";
;
VOLTAGE"3.3V"
HDL_POWER"XP3R3V_FPGA"
BODY_TYPE"PLUMBING"
CDS_LIB"cls"
CDS_LMAN_SYM_OUTLINE"-250,250,250,-250";
"$PIN0"21;
%"RESISTOR"
"2","(-10700,6900)","3","passive","I237";
;
CDS_LOCATION"R157"
PACKAGE"0402"
VALUE"100OHM"
CLS_PN"G155-11000-01"
CDS_LIB"passive"
CDS_LMAN_SYM_OUTLINE"-50,50,50,-100"
TOLERANCE"1%"
LOCATION"R157"
$SEC"1"
CDS_SEC"1";
"1"
$PN"1"36;
"2"
$PN"2"40;
%"74HCT2G125DP_TSSOP8"
"1","(-9500,4950)","0","stdlogic","I255";
;
CDS_LOCATION"U15"
CLS_PN"G220-00055-01"
VALUE"NC7WV125K8X"
CDS_LIB"stdlogic"
CDS_LMAN_SYM_OUTLINE"0,0,500,-500"
LOCATION"U15"
$SEC"1"
CDS_SEC"1";
"VCC"
$PN"8"20;
"2OE* \B"
$PN"7"37;
"1Y"
$PN"6"54;
"2A"
$PN"5"54;
"GND"
$PN"4"18;
"2Y"
$PN"3"61;
"1A"
$PN"2"60;
"1OE* \B"
$PN"1"31;
%"RESISTOR"
"2","(-6350,4750)","3","passive","I257";
;
CDS_LOCATION"R127"
PACKAGE"0402"
VALUE"49.9OHM"
CDS_LIB"passive"
CDS_LMAN_SYM_OUTLINE"-50,50,50,-100"
TOLERANCE"1%"
CLS_PN"G155-149R9-01"
LOCATION"R127"
$SEC"1"
CDS_SEC"1";
"1"
$PN"1"54;
"2"
$PN"2"33;
%"RESISTOR"
"2","(-6350,4650)","3","passive","I258";
;
CDS_LOCATION"R371"
PACKAGE"0402"
VALUE"49.9OHM"
CLS_PN"G155-149R9-01"
TOLERANCE"1%"
CDS_LIB"passive"
CDS_LMAN_SYM_OUTLINE"-50,50,50,-100"
LOCATION"R371"
$SEC"1"
CDS_SEC"1";
"1"
$PN"1"61;
"2"
$PN"2"49;
%"VCC"
"1","(-8450,5000)","0","cls","I259";
;
VOLTAGE"3.3V"
HDL_POWER"XP3R3V_FPGA"
BODY_TYPE"PLUMBING"
CDS_LMAN_SYM_OUTLINE"-250,250,250,-250"
CDS_LIB"cls";
"$PIN0"20;
%"RESISTOR"
"2","(-10700,5200)","1","passive","I261";
;
CDS_LOCATION"R361"
PACKAGE"0402"
VALUE"4.7KOHM"
CDS_LIB"passive"
CDS_LMAN_SYM_OUTLINE"-50,50,50,-100"
CLS_PN"G155-14701-01"
TOLERANCE"1%"
LOCATION"R361"
$SEC"1"
CDS_SEC"1";
"1"
$PN"1"19;
"2"
$PN"2"31;
%"RESISTOR"
"2","(-10700,5100)","1","passive","I262";
;
CDS_LOCATION"R381"
PACKAGE"0402"
VALUE"4.7KOHM"
CDS_LIB"passive"
CDS_LMAN_SYM_OUTLINE"-50,50,50,-100"
CLS_PN"G155-14701-01"
TOLERANCE"1%"
LOCATION"R381"
$SEC"1"
CDS_SEC"1";
"1"
$PN"1"19;
"2"
$PN"2"37;
%"VCC"
"1","(-11350,5350)","0","cls","I264";
;
VOLTAGE"3.3V"
HDL_POWER"XP3R3V_FPGA"
BODY_TYPE"PLUMBING"
CDS_LMAN_SYM_OUTLINE"-250,250,250,-250"
CDS_LIB"cls";
"$PIN0"19;
%"RESISTOR"
"2","(-10700,4750)","3","passive","I265";
;
CDS_LOCATION"R120"
PACKAGE"0402"
VALUE"100OHM"
CLS_PN"G155-11000-01"
TOLERANCE"1%"
CDS_LIB"passive"
CDS_LMAN_SYM_OUTLINE"-50,50,50,-100"
LOCATION"R120"
$SEC"1"
CDS_SEC"1";
"1"
$PN"1"27;
"2"
$PN"2"60;
%"GND_SG"
"1","(-8750,4100)","0","cls","I271";
;
HDL_POWER"SG"
BODY_TYPE"PLUMBING"
CDS_LIB"cls"
CDS_LMAN_SYM_OUTLINE"0,0,100,-50";
"SGND"18;
%"CAPACITOR"
"2","(-8400,4450)","0","passive","I272";
;
PACKAGE"0402"
VALUE"0.1UF"
VOLTAGE"10V"
TOLERANCE"10%"
CLS_PN"G105-0B104-CK"
CDS_LMAN_SYM_OUTLINE"-50,0,50,-50"
CDS_LIB"passive"
$LOCATION"C85"
CDS_LOCATION"C85"
$SEC"1"
CDS_SEC"1";
"2"
$PN"2"18;
"1"
$PN"1"20;
%"74HCT2G125DP_TSSOP8"
"1","(-9450,2800)","0","stdlogic","I273";
;
CDS_LOCATION"U16"
VALUE"NC7WV125K8X"
CLS_PN"G220-00055-01"
CDS_LIB"stdlogic"
CDS_LMAN_SYM_OUTLINE"0,0,500,-500"
LOCATION"U16"
$SEC"1"
CDS_SEC"1";
"VCC"
$PN"8"17;
"2OE* \B"
$PN"7"29;
"1Y"
$PN"6"53;
"2A"
$PN"5"53;
"GND"
$PN"4"16;
"2Y"
$PN"3"50;
"1A"
$PN"2"55;
"1OE* \B"
$PN"1"28;
%"RESISTOR"
"2","(-6300,2500)","3","passive","I275";
;
CDS_LOCATION"R372"
VALUE"49.9OHM"
PACKAGE"0402"
CDS_LMAN_SYM_OUTLINE"-50,50,50,-100"
CDS_LIB"passive"
TOLERANCE"1%"
CLS_PN"G155-149R9-01"
LOCATION"R372"
$SEC"1"
CDS_SEC"1";
"1"
$PN"1"50;
"2"
$PN"2"62;
%"RESISTOR"
"2","(-6300,2600)","3","passive","I276";
;
CDS_LOCATION"R126"
PACKAGE"0402"
VALUE"49.9OHM"
CDS_LIB"passive"
CDS_LMAN_SYM_OUTLINE"-50,50,50,-100"
TOLERANCE"1%"
CLS_PN"G155-149R9-01"
LOCATION"R126"
$SEC"1"
CDS_SEC"1";
"1"
$PN"1"53;
"2"
$PN"2"32;
%"VCC"
"1","(-8400,2850)","0","cls","I277";
;
HDL_POWER"XP3R3V_FPGA"
VOLTAGE"3.3V"
BODY_TYPE"PLUMBING"
CDS_LMAN_SYM_OUTLINE"-250,250,250,-250"
CDS_LIB"cls";
"$PIN0"17;
%"GND_SG"
"1","(-8700,1950)","0","cls","I279";
;
HDL_POWER"SG"
BODY_TYPE"PLUMBING"
CDS_LIB"cls"
CDS_LMAN_SYM_OUTLINE"0,0,100,-50";
"SGND"16;
%"RESISTOR"
"2","(-10650,3050)","1","passive","I280";
;
CDS_LOCATION"R331"
PACKAGE"0402"
VALUE"4.7KOHM"
CDS_LIB"passive"
CDS_LMAN_SYM_OUTLINE"-50,50,50,-100"
CLS_PN"G155-14701-01"
TOLERANCE"1%"
LOCATION"R331"
$SEC"1"
CDS_SEC"1";
"1"
$PN"1"15;
"2"
$PN"2"28;
%"RESISTOR"
"2","(-10650,2950)","1","passive","I281";
;
CDS_LOCATION"R383"
PACKAGE"0402"
VALUE"4.7KOHM"
CDS_LIB"passive"
CDS_LMAN_SYM_OUTLINE"-50,50,50,-100"
CLS_PN"G155-14701-01"
TOLERANCE"1%"
LOCATION"R383"
$SEC"1"
CDS_SEC"1";
"1"
$PN"1"15;
"2"
$PN"2"29;
%"VCC"
"1","(-11300,3200)","0","cls","I282";
;
HDL_POWER"XP3R3V_FPGA"
VOLTAGE"3.3V"
BODY_TYPE"PLUMBING"
CDS_LMAN_SYM_OUTLINE"-250,250,250,-250"
CDS_LIB"cls";
"$PIN0"15;
%"RESISTOR"
"2","(-10650,2600)","3","passive","I284";
;
CDS_LOCATION"R121"
VALUE"100OHM"
PACKAGE"0402"
CLS_PN"G155-11000-01"
TOLERANCE"1%"
CDS_LIB"passive"
CDS_LMAN_SYM_OUTLINE"-50,50,50,-100"
LOCATION"R121"
$SEC"1"
CDS_SEC"1";
"1"
$PN"1"46;
"2"
$PN"2"55;
%"CAPACITOR"
"2","(-8350,2300)","0","passive","I289";
;
VALUE"0.1UF"
VOLTAGE"10V"
PACKAGE"0402"
CDS_LMAN_SYM_OUTLINE"-50,0,50,-50"
CDS_LIB"passive"
TOLERANCE"10%"
CLS_PN"G105-0B104-CK"
$LOCATION"C84"
CDS_LOCATION"C84"
$SEC"1"
CDS_SEC"1";
"2"
$PN"2"16;
"1"
$PN"1"17;
%"CONN_JACK_1P_GH4_S_TH"
"1","(-2650,9150)","0","connector","I290";
;
CDS_LOCATION"J1"
CLS_PN"G200-13091-01"
VALUE"2081680-1"
CDS_LMAN_SYM_OUTLINE"0,0,500,-600"
CDS_LIB"connector"
LOCATION"J1"
$SEC"1"
CDS_SEC"1";
"GH4"
$PN"GH4"2;
"GH3"
$PN"GH3"14;
"GH2"
$PN"GH2"2;
"GH1"
$PN"GH1"14;
"1"
$PN"1"52;
%"GND_SG"
"1","(-2950,8550)","0","cls","I291";
;
HDL_POWER"SG"
BODY_TYPE"PLUMBING"
CDS_LIB"cls"
CDS_LMAN_SYM_OUTLINE"0,0,100,-50";
"SGND"14;
%"GND_SG"
"1","(-2900,6400)","0","cls","I292";
;
HDL_POWER"SG"
BODY_TYPE"PLUMBING"
CDS_LIB"cls"
CDS_LMAN_SYM_OUTLINE"0,0,100,-50";
"SGND"13;
%"GND_SG"
"1","(-1900,6400)","0","cls","I293";
;
HDL_POWER"SG"
BODY_TYPE"PLUMBING"
CDS_LMAN_SYM_OUTLINE"0,0,100,-50"
CDS_LIB"cls";
"SGND"12;
%"CONN_JACK_1P_GH4_S_TH"
"1","(-2600,7000)","0","connector","I294";
;
CDS_LOCATION"J2"
CLS_PN"G200-13091-01"
VALUE"2081680-1"
CDS_LMAN_SYM_OUTLINE"0,0,500,-600"
CDS_LIB"connector"
LOCATION"J2"
$SEC"1"
CDS_SEC"1";
"GH4"
$PN"GH4"12;
"GH3"
$PN"GH3"13;
"GH2"
$PN"GH2"12;
"GH1"
$PN"GH1"13;
"1"
$PN"1"47;
%"GND_SG"
"1","(-2900,4250)","0","cls","I295";
;
HDL_POWER"SG"
BODY_TYPE"PLUMBING"
CDS_LIB"cls"
CDS_LMAN_SYM_OUTLINE"0,0,100,-50";
"SGND"11;
%"GND_SG"
"1","(-1900,4250)","0","cls","I296";
;
HDL_POWER"SG"
BODY_TYPE"PLUMBING"
CDS_LMAN_SYM_OUTLINE"0,0,100,-50"
CDS_LIB"cls";
"SGND"10;
%"CONN_JACK_1P_GH4_S_TH"
"1","(-2600,4850)","0","connector","I297";
;
CDS_LOCATION"J3"
CLS_PN"G200-13091-01"
VALUE"2081680-1"
CDS_LMAN_SYM_OUTLINE"0,0,500,-600"
CDS_LIB"connector"
LOCATION"J3"
$SEC"1"
CDS_SEC"1";
"GH4"
$PN"GH4"10;
"GH3"
$PN"GH3"11;
"GH2"
$PN"GH2"10;
"GH1"
$PN"GH1"11;
"1"
$PN"1"33;
%"GND_SG"
"1","(-2850,2100)","0","cls","I298";
;
HDL_POWER"SG"
BODY_TYPE"PLUMBING"
CDS_LIB"cls"
CDS_LMAN_SYM_OUTLINE"0,0,100,-50";
"SGND"9;
%"GND_SG"
"1","(-1850,2100)","0","cls","I299";
;
HDL_POWER"SG"
BODY_TYPE"PLUMBING"
CDS_LMAN_SYM_OUTLINE"0,0,100,-50"
CDS_LIB"cls";
"SGND"8;
%"CONN_JACK_1P_GH4_S_TH"
"1","(-2550,2700)","0","connector","I300";
;
CDS_LOCATION"J4"
VALUE"2081680-1"
CLS_PN"G200-13091-01"
CDS_LMAN_SYM_OUTLINE"0,0,500,-600"
CDS_LIB"connector"
LOCATION"J4"
$SEC"1"
CDS_SEC"1";
"GH4"
$PN"GH4"8;
"GH3"
$PN"GH3"9;
"GH2"
$PN"GH2"8;
"GH1"
$PN"GH1"9;
"1"
$PN"1"32;
%"GND_SG"
"1","(-10050,8000)","0","cls","I317";
;
HDL_POWER"SG"
BODY_TYPE"PLUMBING"
CDS_LMAN_SYM_OUTLINE"0,0,100,-50"
CDS_LIB"cls";
"SGND"7;
%"CAPACITOR"
"1","(-10000,8250)","1","passive","I318";
;
VALUE"18PF"
PACKAGE"0201"
CDS_LIB"passive"
CDS_LMAN_SYM_OUTLINE"0,50,50,-50"
CLS_PN"G104-0A180-FJ"
TOLERANCE"5%"
$LOCATION"C310"
CDS_LOCATION"C310"
$SEC"1"
CDS_SEC"1";
"2"
$PN"2"59;
"1"
$PN"1"7;
%"RESISTOR"
"2","(-10000,8600)","6","passive","I319";
;
VALUE"0OHM"
PACKAGE"0402"
CLS_PN"G155-100R0-J0"
TOLERANCE"-"
CDS_LIB"passive"
CDS_LMAN_SYM_OUTLINE"-50,50,50,-100"
$LOCATION"R492"
CDS_LOCATION"R492"
$SEC"1"
CDS_SEC"1";
"1"
$PN"1"59;
"2"
$PN"2"43;
%"RESISTOR"
"2","(-9750,8350)","4","passive","I320";
;
VALUE"1MOHM"
PACKAGE"0402"
CDS_LIB"passive"
CDS_LMAN_SYM_OUTLINE"-50,50,50,-100"
TOLERANCE"1%"
CLS_PN"G155-11004-01"
$LOCATION"R496"
CDS_LOCATION"R496"
$SEC"1"
CDS_SEC"1";
"1"
$PN"1"7;
"2"
$PN"2"41;
%"CAPACITOR"
"1","(-9950,6100)","1","passive","I321";
;
VALUE"18PF"
PACKAGE"0201"
TOLERANCE"5%"
CLS_PN"G104-0A180-FJ"
CDS_LMAN_SYM_OUTLINE"0,50,50,-50"
CDS_LIB"passive"
$LOCATION"C311"
CDS_LOCATION"C311"
$SEC"1"
CDS_SEC"1";
"2"
$PN"2"58;
"1"
$PN"1"6;
%"RESISTOR"
"2","(-9700,6200)","4","passive","I322";
;
VALUE"1MOHM"
PACKAGE"0402"
CLS_PN"G155-11004-01"
TOLERANCE"1%"
CDS_LMAN_SYM_OUTLINE"-50,50,50,-100"
CDS_LIB"passive"
$LOCATION"R497"
CDS_LOCATION"R497"
$SEC"1"
CDS_SEC"1";
"1"
$PN"1"6;
"2"
$PN"2"44;
%"RESISTOR"
"2","(-9950,6450)","6","passive","I323";
;
VALUE"0OHM"
PACKAGE"0402"
CLS_PN"G155-100R0-J0"
TOLERANCE"-"
CDS_LMAN_SYM_OUTLINE"-50,50,50,-100"
CDS_LIB"passive"
$LOCATION"R493"
CDS_LOCATION"R493"
$SEC"1"
CDS_SEC"1";
"1"
$PN"1"58;
"2"
$PN"2"40;
%"GND_SG"
"1","(-10000,5850)","0","cls","I324";
;
HDL_POWER"SG"
CDS_LIB"cls"
CDS_LMAN_SYM_OUTLINE"0,0,100,-50"
BODY_TYPE"PLUMBING";
"SGND"6;
%"GND_SG"
"1","(-10000,3700)","0","cls","I325";
;
HDL_POWER"SG"
BODY_TYPE"PLUMBING"
CDS_LMAN_SYM_OUTLINE"0,0,100,-50"
CDS_LIB"cls";
"SGND"5;
%"RESISTOR"
"2","(-9950,4300)","6","passive","I326";
;
PACKAGE"0402"
VALUE"0OHM"
CLS_PN"G155-100R0-J0"
TOLERANCE"-"
CDS_LIB"passive"
CDS_LMAN_SYM_OUTLINE"-50,50,50,-100"
$LOCATION"R494"
CDS_LOCATION"R494"
$SEC"1"
CDS_SEC"1";
"1"
$PN"1"57;
"2"
$PN"2"60;
%"RESISTOR"
"2","(-9700,4050)","4","passive","I327";
;
VALUE"1MOHM"
PACKAGE"0402"
CDS_LIB"passive"
CDS_LMAN_SYM_OUTLINE"-50,50,50,-100"
TOLERANCE"1%"
CLS_PN"G155-11004-01"
$LOCATION"R498"
CDS_LOCATION"R498"
$SEC"1"
CDS_SEC"1";
"1"
$PN"1"5;
"2"
$PN"2"54;
%"CAPACITOR"
"1","(-9950,3950)","1","passive","I328";
;
VALUE"18PF"
PACKAGE"0201"
CDS_LIB"passive"
CDS_LMAN_SYM_OUTLINE"0,50,50,-50"
CLS_PN"G104-0A180-FJ"
TOLERANCE"5%"
$LOCATION"C317"
CDS_LOCATION"C317"
$SEC"1"
CDS_SEC"1";
"2"
$PN"2"57;
"1"
$PN"1"5;
%"GND_SG"
"1","(-9950,1550)","0","cls","I329";
;
HDL_POWER"SG"
CDS_LIB"cls"
CDS_LMAN_SYM_OUTLINE"0,0,100,-50"
BODY_TYPE"PLUMBING";
"SGND"4;
%"RESISTOR"
"2","(-9900,2150)","6","passive","I330";
;
VALUE"0OHM"
PACKAGE"0402"
CLS_PN"G155-100R0-J0"
TOLERANCE"-"
CDS_LMAN_SYM_OUTLINE"-50,50,50,-100"
CDS_LIB"passive"
$LOCATION"R495"
CDS_LOCATION"R495"
$SEC"1"
CDS_SEC"1";
"1"
$PN"1"56;
"2"
$PN"2"55;
%"RESISTOR"
"2","(-9650,1900)","4","passive","I331";
;
VALUE"1MOHM"
PACKAGE"0402"
CLS_PN"G155-11004-01"
TOLERANCE"1%"
CDS_LMAN_SYM_OUTLINE"-50,50,50,-100"
CDS_LIB"passive"
$LOCATION"R499"
CDS_LOCATION"R499"
$SEC"1"
CDS_SEC"1";
"1"
$PN"1"4;
"2"
$PN"2"53;
%"CAPACITOR"
"1","(-9900,1800)","1","passive","I332";
;
VALUE"18PF"
PACKAGE"0201"
TOLERANCE"5%"
CLS_PN"G104-0A180-FJ"
CDS_LMAN_SYM_OUTLINE"0,50,50,-50"
CDS_LIB"passive"
$LOCATION"C318"
CDS_LOCATION"C318"
$SEC"1"
CDS_SEC"1";
"2"
$PN"2"56;
"1"
$PN"1"4;
%"GND_SG"
"1","(-3750,7500)","0","cls","I41";
;
HDL_POWER"SG"
BODY_TYPE"PLUMBING"
CDS_LIB"cls"
CDS_LMAN_SYM_OUTLINE"0,0,100,-50";
"SGND"3;
%"DIODE_4_V1"
"1","(-3800,7700)","1","discrete","I42";
;
CLS_PN"G122-10123-01"
PART_NUMBER"SR3.3.TCT"
CDS_LIB"discrete"
CDS_LMAN_SYM_OUTLINE"0,0,400,-600"
$LOCATION"CR5"
CDS_LOCATION"CR5"
$SEC"1"
CDS_SEC"1";
"VDD"
$PN"4"0;
"IO2"
$PN"3"52;
"IO1"
$PN"2"47;
"GND"
$PN"1"3;
%"GND_SG"
"1","(-1950,8550)","0","cls","I55";
;
HDL_POWER"SG"
BODY_TYPE"PLUMBING"
CDS_LMAN_SYM_OUTLINE"0,0,100,-50"
CDS_LIB"cls";
"SGND"2;
%"RESISTOR"
"2","(-10750,9050)","3","passive","I63";
;
VALUE"100OHM"
PACKAGE"0402"
CLS_PN"G155-11000-01"
TOLERANCE"1%"
CDS_LIB"passive"
CDS_LMAN_SYM_OUTLINE"-50,50,50,-100"
$LOCATION"R156"
CDS_LOCATION"R156"
$SEC"1"
CDS_SEC"1";
"1"
$PN"1"38;
"2"
$PN"2"43;
%"RESISTOR"
"2","(-10750,9500)","1","passive","I88";
;
PACKAGE"0402"
VALUE"4.7KOHM"
CDS_LIB"passive"
CDS_LMAN_SYM_OUTLINE"-50,50,50,-100"
CLS_PN"G155-14701-01"
TOLERANCE"1%"
$LOCATION"R365"
CDS_LOCATION"R365"
$SEC"1"
CDS_SEC"1";
"1"
$PN"1"1;
"2"
$PN"2"30;
%"VCC"
"1","(-11400,9650)","0","cls","I89";
;
VOLTAGE"3.3V"
HDL_POWER"XP3R3V_FPGA"
BODY_TYPE"PLUMBING"
CDS_LMAN_SYM_OUTLINE"-250,250,250,-250"
CDS_LIB"cls";
"$PIN0"1;
END.
